(kicad_pcb
	(version 20241229)
	(generator "pcbnew")
	(generator_version "9.0")
	(general
		(thickness 1.61)
		(legacy_teardrops no)
	)
	(paper "A3")
	(title_block
		(title "RDIMM DDR5 Tester")
		(date "2026-05-21")
		(rev "2.2.0")
		(company "Antmicro")
		(comment 9 "footprint 119 of 796 (U34), pads 1-67 of 676")
	)
	(layers
		(0 "F.Cu" signal)
		(4 "In1.Cu" power)
		(6 "In2.Cu" mixed)
		(8 "In3.Cu" power)
		(10 "In4.Cu" mixed)
		(12 "In5.Cu" power)
		(14 "In6.Cu" mixed)
		(16 "In7.Cu" power)
		(18 "In8.Cu" power)
		(20 "In9.Cu" mixed)
		(22 "In10.Cu" power)
		(2 "B.Cu" signal)
		(9 "F.Adhes" user "F.Adhesive")
		(11 "B.Adhes" user "B.Adhesive")
		(13 "F.Paste" user)
		(15 "B.Paste" user)
		(5 "F.SilkS" user "F.Silkscreen")
		(7 "B.SilkS" user "B.Silkscreen")
		(1 "F.Mask" user)
		(3 "B.Mask" user)
		(17 "Dwgs.User" user "User.Drawings")
		(19 "Cmts.User" user "User.Comments")
		(21 "Eco1.User" user "User.Eco1")
		(23 "Eco2.User" user "User.Eco2")
		(25 "Edge.Cuts" user)
		(27 "Margin" user)
		(31 "F.CrtYd" user "F.Courtyard")
		(29 "B.CrtYd" user "B.Courtyard")
		(35 "F.Fab" user)
		(33 "B.Fab" user)
	)
	(footprint "antmicro-footprints:BGA-676_27x27mm_Layout26x26_P1x1mm_FFVB676"
		(layer "F.Cu")
		(at 188.5 152.5 90)
		(property "Reference" "U34"
			(at -14.72 12.46 180)
			(layer "F.SilkS")
			(effects
				(font
					(size 0.7 0.7)
					(thickness 0.15)
				)
				(justify left bottom)
			)
		)
		(property "Value" "XCAU25P-2FFVB676I"
			(at 0 15.5 90)
			(layer "F.Fab")
			(effects
				(font
					(size 0.7 0.7)
					(thickness 0.15)
				)
				(justify left bottom)
			)
		)
		(property "Datasheet" "https://docs.xilinx.com/viewer/book-attachment/2PXOpPtpaABIt0fkzeBLnw/hvbsEUaOT0OxFhln7VEVyA"
			(at 0 0 90)
			(layer "F.Fab")
			(hide yes)
			(effects
				(font
					(size 1.27 1.27)
					(thickness 0.15)
				)
			)
		)
		(property "MPN" "XCAU25P-2FFVB676I"
			(at 0 0 90)
			(unlocked yes)
			(layer "F.Fab")
			(hide yes)
			(effects
				(font
					(size 1 1)
					(thickness 0.15)
				)
			)
		)
		(property "Manufacturer" "AMD-Xilinx"
			(at 0 0 90)
			(unlocked yes)
			(layer "F.Fab")
			(hide yes)
			(effects
				(font
					(size 1 1)
					(thickness 0.15)
				)
			)
		)
		(property "Author" "Antmicro"
			(at 0 0 90)
			(unlocked yes)
			(layer "F.Fab")
			(hide yes)
			(effects
				(font
					(size 1 1)
					(thickness 0.15)
				)
			)
		)
		(property "License" "Apache-2.0"
			(at 0 0 90)
			(unlocked yes)
			(layer "F.Fab")
			(hide yes)
			(effects
				(font
					(size 1 1)
					(thickness 0.15)
				)
			)
		)
		(sheetname "/FPGA Config/")
		(sheetfile "fpga-config.kicad_sch")
		(attr smd)
		(pad "A1" smd circle
			(at -12.5 -12.5 90)
			(size 0.5 0.5)
			(layers "F.Cu" "F.Mask" "F.Paste")
			(net 1 "GND")
			(pinfunction "GND")
			(pintype "power_in")
			(solder_mask_margin 0.075)
		)
		(pad "A2" smd circle
			(at -11.5 -12.5 90)
			(size 0.5 0.5)
			(layers "F.Cu" "F.Mask" "F.Paste")
			(net 1 "GND")
			(pinfunction "GND")
			(pintype "passive")
			(solder_mask_margin 0.075)
		)
		(pad "A3" smd circle
			(at -10.5 -12.5 90)
			(size 0.5 0.5)
			(layers "F.Cu" "F.Mask" "F.Paste")
			(net 463 "unconnected-(U34L-NC-PadA3)")
			(pinfunction "NC")
			(pintype "no_connect")
			(solder_mask_margin 0.075)
		)
		(pad "A4" smd circle
			(at -9.5 -12.5 90)
			(size 0.5 0.5)
			(layers "F.Cu" "F.Mask" "F.Paste")
			(net 464 "unconnected-(U34L-NC-PadA4)")
			(pinfunction "NC")
			(pintype "no_connect")
			(solder_mask_margin 0.075)
		)
		(pad "A5" smd circle
			(at -8.5 -12.5 90)
			(size 0.5 0.5)
			(layers "F.Cu" "F.Mask" "F.Paste")
			(net 1 "GND")
			(pinfunction "GND")
			(pintype "passive")
			(solder_mask_margin 0.075)
		)
		(pad "A6" smd circle
			(at -7.5 -12.5 90)
			(size 0.5 0.5)
			(layers "F.Cu" "F.Mask" "F.Paste")
			(net 1 "GND")
			(pinfunction "GND")
			(pintype "passive")
			(solder_mask_margin 0.075)
		)
		(pad "A7" smd circle
			(at -6.5 -12.5 90)
			(size 0.5 0.5)
			(layers "F.Cu" "F.Mask" "F.Paste")
			(net 172 "+1V2_MGTAVTT")
			(pinfunction "MGTAVTT_R")
			(pintype "input")
			(solder_mask_margin 0.075)
		)
		(pad "A8" smd circle
			(at -5.5 -12.5 90)
			(size 0.5 0.5)
			(layers "F.Cu" "F.Mask" "F.Paste")
			(net 1 "GND")
			(pinfunction "GND")
			(pintype "passive")
			(solder_mask_margin 0.075)
		)
		(pad "A9" smd circle
			(at -4.5 -12.5 90)
			(size 0.5 0.5)
			(layers "F.Cu" "F.Mask" "F.Paste")
			(net 406 "/Debug FTDI + VNA/AUX.TDO")
			(pinfunction "IO_L10N_AD2N_86")
			(pintype "bidirectional")
			(die_length 19.481)
			(solder_mask_margin 0.075)
		)
		(pad "A10" smd circle
			(at -3.5 -12.5 90)
			(size 0.5 0.5)
			(layers "F.Cu" "F.Mask" "F.Paste")
			(net 98 "PCIE.PWRGD")
			(pinfunction "IO_L11N_AD1N_86")
			(pintype "bidirectional")
			(die_length 18.317)
			(solder_mask_margin 0.075)
		)
		(pad "A11" smd circle
			(at -2.5 -12.5 90)
			(size 0.5 0.5)
			(layers "F.Cu" "F.Mask" "F.Paste")
			(net 1 "GND")
			(pinfunction "GND")
			(pintype "passive")
			(solder_mask_margin 0.075)
		)
		(pad "A12" smd circle
			(at -1.5 -12.5 90)
			(size 0.5 0.5)
			(layers "F.Cu" "F.Mask" "F.Paste")
			(net 762 "INT_CB")
			(pinfunction "IO_L11N_AD9N_87")
			(pintype "bidirectional")
			(die_length 15.339)
			(solder_mask_margin 0.075)
		)
		(pad "A13" smd circle
			(at -0.5 -12.5 90)
			(size 0.5 0.5)
			(layers "F.Cu" "F.Mask" "F.Paste")
			(net 531 "~{SI_5319_RST}")
			(pinfunction "IO_L11P_AD9P_87")
			(pintype "bidirectional")
			(die_length 14.63)
			(solder_mask_margin 0.075)
		)
		(pad "A14" smd circle
			(at 0.5 -12.5 90)
			(size 0.5 0.5)
			(layers "F.Cu" "F.Mask" "F.Paste")
			(net 767 "LOL")
			(pinfunction "IO_L12N_AD8N_87")
			(pintype "bidirectional")
			(die_length 13.531)
			(solder_mask_margin 0.075)
		)
		(pad "A15" smd circle
			(at 1.5 -12.5 90)
			(size 0.5 0.5)
			(layers "F.Cu" "F.Mask" "F.Paste")
			(net 396 "/Ethernet/ETH.RXD3")
			(pinfunction "IO_L17N_T2U_N9_AD10N_67")
			(pintype "bidirectional")
			(die_length 17.775)
			(solder_mask_margin 0.075)
		)
		(pad "A16" smd circle
			(at 2.5 -12.5 90)
			(size 0.5 0.5)
			(layers "F.Cu" "F.Mask" "F.Paste")
			(net 1 "GND")
			(pinfunction "GND")
			(pintype "passive")
			(solder_mask_margin 0.075)
		)
		(pad "A17" smd circle
			(at 3.5 -12.5 90)
			(size 0.5 0.5)
			(layers "F.Cu" "F.Mask" "F.Paste")
			(net 438 "/Ethernet/ETH.TXD3")
			(pinfunction "IO_L16P_T2U_N6_QBC_AD3P_67")
			(pintype "bidirectional")
			(die_length 17.349)
			(solder_mask_margin 0.075)
		)
		(pad "A18" smd circle
			(at 4.5 -12.5 90)
			(size 0.5 0.5)
			(layers "F.Cu" "F.Mask" "F.Paste")
			(net 440 "/Ethernet/ETH.TXD1")
			(pinfunction "IO_L16N_T2U_N7_QBC_AD3N_67")
			(pintype "bidirectional")
			(die_length 17.459)
			(solder_mask_margin 0.075)
		)
		(pad "A19" smd circle
			(at 5.5 -12.5 90)
			(size 0.5 0.5)
			(layers "F.Cu" "F.Mask" "F.Paste")
			(net 393 "/Ethernet/ETH.RXD0")
			(pinfunction "IO_L18P_T2U_N10_AD2P_67")
			(pintype "bidirectional")
			(die_length 15.262)
			(solder_mask_margin 0.075)
		)
		(pad "A20" smd circle
			(at 6.5 -12.5 90)
			(size 0.5 0.5)
			(layers "F.Cu" "F.Mask" "F.Paste")
			(net 439 "/Ethernet/ETH.TXD2")
			(pinfunction "IO_L18N_T2U_N11_AD2N_67")
			(pintype "bidirectional")
			(die_length 15.054)
			(solder_mask_margin 0.075)
		)
		(pad "A21" smd circle
			(at 7.5 -12.5 90)
			(size 0.5 0.5)
			(layers "F.Cu" "F.Mask" "F.Paste")
			(net 1 "GND")
			(pinfunction "GND")
			(pintype "passive")
			(solder_mask_margin 0.075)
		)
		(pad "A22" smd circle
			(at 8.5 -12.5 90)
			(size 0.5 0.5)
			(layers "F.Cu" "F.Mask" "F.Paste")
			(net 665 "unconnected-(U34E-IO_L19P_T3L_N0_DBC_AD9P_67-PadA22)")
			(pinfunction "IO_L19P_T3L_N0_DBC_AD9P_67")
			(pintype "bidirectional+no_connect")
			(die_length 14.598)
			(solder_mask_margin 0.075)
		)
		(pad "A23" smd circle
			(at 9.5 -12.5 90)
			(size 0.5 0.5)
			(layers "F.Cu" "F.Mask" "F.Paste")
			(net 469 "unconnected-(U34E-IO_L19N_T3L_N1_DBC_AD9N_67-PadA23)")
			(pinfunction "IO_L19N_T3L_N1_DBC_AD9N_67")
			(pintype "bidirectional+no_connect")
			(die_length 14.59)
			(solder_mask_margin 0.075)
		)
		(pad "A24" smd circle
			(at 10.5 -12.5 90)
			(size 0.5 0.5)
			(layers "F.Cu" "F.Mask" "F.Paste")
			(net 400 "/Ethernet/ETH.MDIO")
			(pinfunction "IO_L23P_T3U_N8_67")
			(pintype "bidirectional")
			(die_length 15.06)
			(solder_mask_margin 0.075)
		)
		(pad "A25" smd circle
			(at 11.5 -12.5 90)
			(size 0.5 0.5)
			(layers "F.Cu" "F.Mask" "F.Paste")
			(net 437 "/Ethernet/ETH.~{INT}")
			(pinfunction "IO_L23N_T3U_N9_67")
			(pintype "bidirectional")
			(die_length 15.012)
			(solder_mask_margin 0.075)
		)
		(pad "A26" smd circle
			(at 12.5 -12.5 90)
			(size 0.5 0.5)
			(layers "F.Cu" "F.Mask" "F.Paste")
			(net 1 "GND")
			(pinfunction "GND")
			(pintype "passive")
			(solder_mask_margin 0.075)
		)
		(pad "AA1" smd circle
			(at -12.5 7.5 90)
			(size 0.5 0.5)
			(layers "F.Cu" "F.Mask" "F.Paste")
			(net 1 "GND")
			(pinfunction "GND")
			(pintype "passive")
			(solder_mask_margin 0.075)
		)
		(pad "AA2" smd circle
			(at -11.5 7.5 90)
			(size 0.5 0.5)
			(layers "F.Cu" "F.Mask" "F.Paste")
			(net 1 "GND")
			(pinfunction "GND")
			(pintype "passive")
			(solder_mask_margin 0.075)
		)
		(pad "AA3" smd circle
			(at -10.5 7.5 90)
			(size 0.5 0.5)
			(layers "F.Cu" "F.Mask" "F.Paste")
			(net 1 "GND")
			(pinfunction "GND")
			(pintype "passive")
			(solder_mask_margin 0.075)
		)
		(pad "AA4" smd circle
			(at -9.5 7.5 90)
			(size 0.5 0.5)
			(layers "F.Cu" "F.Mask" "F.Paste")
			(net 24 "/FPGA MGT Interface/GTY_225_TX0_N")
			(pinfunction "MGTYTXN0_225")
			(pintype "output")
			(die_length 9.827)
			(solder_mask_margin 0.075)
		)
		(pad "AA5" smd circle
			(at -8.5 7.5 90)
			(size 0.5 0.5)
			(layers "F.Cu" "F.Mask" "F.Paste")
			(net 16 "/FPGA MGT Interface/GTY_225_TX0_P")
			(pinfunction "MGTYTXP0_225")
			(pintype "output")
			(die_length 9.852)
			(solder_mask_margin 0.075)
		)
		(pad "AA6" smd circle
			(at -7.5 7.5 90)
			(size 0.5 0.5)
			(layers "F.Cu" "F.Mask" "F.Paste")
			(net 1 "GND")
			(pinfunction "GND")
			(pintype "passive")
			(solder_mask_margin 0.075)
		)
		(pad "AA7" smd circle
			(at -6.5 7.5 90)
			(size 0.5 0.5)
			(layers "F.Cu" "F.Mask" "F.Paste")
			(net 820 "+0V9_MGTAVCC")
			(pinfunction "MGTAVCC_R")
			(pintype "power_in")
			(solder_mask_margin 0.075)
		)
		(pad "AA8" smd circle
			(at -5.5 7.5 90)
			(size 0.5 0.5)
			(layers "F.Cu" "F.Mask" "F.Paste")
			(net 1 "GND")
			(pinfunction "GND")
			(pintype "passive")
			(solder_mask_margin 0.075)
		)
		(pad "AA9" smd circle
			(at -4.5 7.5 90)
			(size 0.5 0.5)
			(layers "F.Cu" "F.Mask" "F.Paste")
			(net 1 "GND")
			(pinfunction "M1_0")
			(pintype "input")
			(die_length 14.72)
			(solder_mask_margin 0.075)
		)
		(pad "AA10" smd circle
			(at -3.5 7.5 90)
			(size 0.5 0.5)
			(layers "F.Cu" "F.Mask" "F.Paste")
			(net 356 "/FPGA Config/MODE0")
			(pinfunction "M0_0")
			(pintype "input")
			(die_length 14.957)
			(solder_mask_margin 0.075)
		)
		(pad "AA11" smd circle
			(at -2.5 7.5 90)
			(size 0.5 0.5)
			(layers "F.Cu" "F.Mask" "F.Paste")
			(net 797 "+1V8")
			(pinfunction "VCCO_0")
			(pintype "power_in")
			(solder_mask_margin 0.075)
		)
		(pad "AA12" smd circle
			(at -1.5 7.5 90)
			(size 0.5 0.5)
			(layers "F.Cu" "F.Mask" "F.Paste")
			(net 350 "/FPGA Config/FLASH.~{CS}")
			(pinfunction "RDWR_FCS_B_0")
			(pintype "bidirectional")
			(die_length 15.712)
			(solder_mask_margin 0.075)
		)
		(pad "AA13" smd circle
			(at -0.5 7.5 90)
			(size 0.5 0.5)
			(layers "F.Cu" "F.Mask" "F.Paste")
			(net 471 "unconnected-(U34F-IO_L11N_AD1N_84-PadAA13)")
			(pinfunction "IO_L11N_AD1N_84")
			(pintype "bidirectional+no_connect")
			(die_length 13.282)
			(solder_mask_margin 0.075)
		)
		(pad "AA14" smd circle
			(at 0.5 7.5 90)
			(size 0.5 0.5)
			(layers "F.Cu" "F.Mask" "F.Paste")
			(net 206 "FAN_PWM")
			(pinfunction "IO_L8P_HDGC_AD4P_84")
			(pintype "bidirectional")
			(die_length 12.153)
			(solder_mask_margin 0.075)
		)
		(pad "AA15" smd circle
			(at 1.5 7.5 90)
			(size 0.5 0.5)
			(layers "F.Cu" "F.Mask" "F.Paste")
			(net 184 "FPGA_POWER_CYCLE")
			(pinfunction "IO_L7N_HDGC_AD5N_84")
			(pintype "bidirectional")
			(die_length 12.163)
			(solder_mask_margin 0.075)
		)
		(pad "AA16" smd circle
			(at 2.5 7.5 90)
			(size 0.5 0.5)
			(layers "F.Cu" "F.Mask" "F.Paste")
			(net 1 "GND")
			(pinfunction "GND")
			(pintype "passive")
			(solder_mask_margin 0.075)
		)
		(pad "AA17" smd circle
			(at 3.5 7.5 90)
			(size 0.5 0.5)
			(layers "F.Cu" "F.Mask" "F.Paste")
			(net 134 "/DDR5 RDIMM/A.DQ6")
			(pinfunction "IO_L23N_T3U_N9_64")
			(pintype "bidirectional")
			(die_length 13.433)
			(solder_mask_margin 0.075)
		)
		(pad "AA18" smd circle
			(at 4.5 7.5 90)
			(size 0.5 0.5)
			(layers "F.Cu" "F.Mask" "F.Paste")
			(net 53 "/DDR5 RDIMM/A.DQ4")
			(pinfunction "IO_L24N_T3U_N11_64")
			(pintype "bidirectional")
			(die_length 14.564)
			(solder_mask_margin 0.075)
		)
		(pad "AA19" smd circle
			(at 5.5 7.5 90)
			(size 0.5 0.5)
			(layers "F.Cu" "F.Mask" "F.Paste")
			(net 51 "/DDR5 RDIMM/A.DQ0")
			(pinfunction "IO_L20P_T3L_N2_AD1P_64")
			(pintype "bidirectional")
			(die_length 12.184)
			(solder_mask_margin 0.075)
		)
		(pad "AA20" smd circle
			(at 6.5 7.5 90)
			(size 0.5 0.5)
			(layers "F.Cu" "F.Mask" "F.Paste")
			(net 52 "/DDR5 RDIMM/A.DQ1")
			(pinfunction "IO_L21P_T3L_N4_AD8P_64")
			(pintype "bidirectional")
			(die_length 14.796)
			(solder_mask_margin 0.075)
		)
		(pad "AA21" smd circle
			(at 7.5 7.5 90)
			(size 0.5 0.5)
			(layers "F.Cu" "F.Mask" "F.Paste")
			(net 687 "VDDQ")
			(pinfunction "VCCO_64")
			(pintype "power_in")
			(solder_mask_margin 0.075)
		)
		(pad "AA22" smd circle
			(at 8.5 7.5 90)
			(size 0.5 0.5)
			(layers "F.Cu" "F.Mask" "F.Paste")
			(net 209 "/DDR5 RDIMM/A.DQS7_P")
			(pinfunction "IO_L10P_T1U_N6_QBC_AD4P_64")
			(pintype "bidirectional")
			(die_length 13.153)
			(solder_mask_margin 0.075)
		)
		(pad "AA23" smd circle
			(at 9.5 7.5 90)
			(size 0.5 0.5)
			(layers "F.Cu" "F.Mask" "F.Paste")
			(net 72 "/DDR5 RDIMM/CTRL.~{ALERT}")
			(pinfunction "IO_T1U_N12_SMBALERT_65")
			(pintype "bidirectional")
			(die_length 13.037)
			(solder_mask_margin 0.075)
		)
		(pad "AA24" smd circle
			(at 10.5 7.5 90)
			(size 0.5 0.5)
			(layers "F.Cu" "F.Mask" "F.Paste")
			(net 75 "/DDR5 RDIMM/A.CA2")
			(pinfunction "IO_L9P_T1L_N4_AD12P_A14_D30_65")
			(pintype "bidirectional")
			(die_length 14.273)
			(solder_mask_margin 0.075)
		)
		(pad "AA25" smd circle
			(at 11.5 7.5 90)
			(size 0.5 0.5)
			(layers "F.Cu" "F.Mask" "F.Paste")
			(net 193 "/DDR5 RDIMM/A.CA3")
			(pinfunction "IO_L9N_T1L_N5_AD12N_A15_D31_65")
			(pintype "bidirectional")
			(die_length 14.349)
			(solder_mask_margin 0.075)
		)
		(pad "AA26" smd circle
			(at 12.5 7.5 90)
			(size 0.5 0.5)
			(layers "F.Cu" "F.Mask" "F.Paste")
			(net 1 "GND")
			(pinfunction "GND")
			(pintype "passive")
			(solder_mask_margin 0.075)
		)
		(pad "AB1" smd circle
			(at -12.5 8.5 90)
			(size 0.5 0.5)
			(layers "F.Cu" "F.Mask" "F.Paste")
			(net 584 "/FPGA MGT Interface/PCIE.RXD4_N")
			(pinfunction "MGTYRXN3_224")
			(pintype "input")
			(die_length 13.412)
			(solder_mask_margin 0.075)
		)
		(pad "AB2" smd circle
			(at -11.5 8.5 90)
			(size 0.5 0.5)
			(layers "F.Cu" "F.Mask" "F.Paste")
			(net 583 "/FPGA MGT Interface/PCIE.RXD4_P")
			(pinfunction "MGTYRXP3_224")
			(pintype "input")
			(die_length 13.41)
			(solder_mask_margin 0.075)
		)
		(pad "AB3" smd circle
			(at -10.5 8.5 90)
			(size 0.5 0.5)
			(layers "F.Cu" "F.Mask" "F.Paste")
			(net 1 "GND")
			(pinfunction "GND")
			(pintype "passive")
			(solder_mask_margin 0.075)
		)
		(pad "AB4" smd circle
			(at -9.5 8.5 90)
			(size 0.5 0.5)
			(layers "F.Cu" "F.Mask" "F.Paste")
			(net 1 "GND")
			(pinfunction "GND")
			(pintype "passive")
			(solder_mask_margin 0.075)
		)
		(pad "AB5" smd circle
			(at -8.5 8.5 90)
			(size 0.5 0.5)
			(layers "F.Cu" "F.Mask" "F.Paste")
			(net 172 "+1V2_MGTAVTT")
			(pinfunction "MGTAVTT_R")
			(pintype "passive")
			(solder_mask_margin 0.075)
		)
		(pad "AB6" smd circle
			(at -7.5 8.5 90)
			(size 0.5 0.5)
			(layers "F.Cu" "F.Mask" "F.Paste")
			(net 14 "/FPGA MGT Interface/GTR_REFCLK0_N")
			(pinfunction "MGTREFCLK0N_224")
			(pintype "input")
			(die_length 9.71)
			(solder_mask_margin 0.075)
		)
		(pad "AB7" smd circle
			(at -6.5 8.5 90)
			(size 0.5 0.5)
			(layers "F.Cu" "F.Mask" "F.Paste")
			(net 12 "/FPGA MGT Interface/GTR_REFCLK0_P")
			(pinfunction "MGTREFCLK0P_224")
			(pintype "input")
			(die_length 9.721)
			(solder_mask_margin 0.075)
		)
		(pad "AB8" smd circle
			(at -5.5 8.5 90)
			(size 0.5 0.5)
			(layers "F.Cu" "F.Mask" "F.Paste")
			(net 1 "GND")
			(pinfunction "GND")
			(pintype "passive")
			(solder_mask_margin 0.075)
		)
		(pad "AB9" smd circle
			(at -4.5 8.5 90)
			(size 0.5 0.5)
			(layers "F.Cu" "F.Mask" "F.Paste")
			(net 357 "/FPGA Config/PROGRAM_B")
			(pinfunction "PROGRAM_B_0")
			(pintype "input")
			(die_length 15.843)
			(solder_mask_margin 0.075)
		)
		(pad "AB10" smd circle
			(at -3.5 8.5 90)
			(size 0.5 0.5)
			(layers "F.Cu" "F.Mask" "F.Paste")
			(net 238 "/Debug FTDI + VNA/JTAG.TMS")
			(pinfunction "TMS_0")
			(pintype "input")
			(die_length 14.392)
			(solder_mask_margin 0.075)
		)
		(pad "AB11" smd circle
			(at -2.5 8.5 90)
			(size 0.5 0.5)
			(layers "F.Cu" "F.Mask" "F.Paste")
			(net 340 "/FPGA Config/DONE")
			(pinfunction "DONE_0")
			(pintype "bidirectional")
			(die_length 16.256)
			(solder_mask_margin 0.075)
		)
		(pad "AB12" smd circle
			(at -1.5 8.5 90)
			(size 0.5 0.5)
			(layers "F.Cu" "F.Mask" "F.Paste")
			(net 244 "/Debug FTDI + VNA/JTAG.TDI")
			(pinfunction "TDI_0")
			(pintype "input")
			(die_length 15.226)
			(solder_mask_margin 0.075)
		)
		(pad "AB13" smd circle
			(at -0.5 8.5 90)
			(size 0.5 0.5)
			(layers "F.Cu" "F.Mask" "F.Paste")
			(net 1 "GND")
			(pinfunction "GND")
			(pintype "passive")
			(solder_mask_margin 0.075)
		)
		(pad "AB14" smd circle
			(at 0.5 8.5 90)
			(size 0.5 0.5)
			(layers "F.Cu" "F.Mask" "F.Paste")
			(net 478 "unconnected-(U34F-IO_L8N_HDGC_AD4N_84-PadAB14)")
			(pinfunction "IO_L8N_HDGC_AD4N_84")
			(pintype "bidirectional+no_connect")
			(die_length 12.152)
			(solder_mask_margin 0.075)
		)
		(pad "AB15" smd circle
			(at 1.5 8.5 90)
			(size 0.5 0.5)
			(layers "F.Cu" "F.Mask" "F.Paste")
			(net 479 "unconnected-(U34F-IO_L6P_HDGC_AD6P_84-PadAB15)")
			(pinfunction "IO_L6P_HDGC_AD6P_84")
			(pintype "bidirectional+no_connect")
			(die_length 12.373)
			(solder_mask_margin 0.075)
		)
	)
)
